(kicad_pcb
	(version 20260206)
	(generator "pcbnew")
	(generator_version "10.0")
	(general
		(thickness 1.6)
		(legacy_teardrops no)
	)
	(paper "A4")
	(title_block
		(title "04192023_DAF0TMB3IC0_F0TG_MB_C_brd_V02_OCP.brd")
		(comment 1 "Grand Teton / footprints 1391-1396 of 8354")
	)
	(layers
		(0 "F.Cu" signal "TOP")
		(4 "In1.Cu" signal "GND")
		(6 "In2.Cu" signal "IN1")
		(8 "In3.Cu" signal "GND1")
		(10 "In4.Cu" signal "IN2")
		(12 "In5.Cu" signal "GND2")
		(14 "In6.Cu" signal "IN3")
		(16 "In7.Cu" signal "GND3")
		(18 "In8.Cu" signal "VCC")
		(20 "In9.Cu" signal "VCC1")
		(22 "In10.Cu" signal "GND4")
		(24 "In11.Cu" signal "IN4")
		(26 "In12.Cu" signal "GND5")
		(28 "In13.Cu" signal "IN5")
		(30 "In14.Cu" signal "GND6")
		(32 "In15.Cu" signal "IN6")
		(34 "In16.Cu" signal "GND7")
		(2 "B.Cu" signal "BOTTOM")
		(9 "F.Adhes" user "F.Adhesive")
		(11 "B.Adhes" user "B.Adhesive")
		(13 "F.Paste" user "Package Geometry/Pastemask Top")
		(15 "B.Paste" user "Package Geometry/Pastemask Bottom")
		(5 "F.SilkS" user "Ref Des/Silkscreen Top")
		(7 "B.SilkS" user "Ref Des/Silkscreen Bottom")
		(1 "F.Mask" user "Board Geometry/Soldermask Top")
		(3 "B.Mask" user "Board Geometry/Soldermask Bottom")
		(17 "Dwgs.User" user "User.Drawings")
		(19 "Cmts.User" user "User.Comments")
		(21 "Eco1.User" user "User.Eco1")
		(23 "Eco2.User" user "User.Eco2")
		(25 "Edge.Cuts" user "Board Geometry/Outline")
		(27 "Margin" user)
		(31 "F.CrtYd" user "Package Geometry/Place Bound Top")
		(29 "B.CrtYd" user "Package Geometry/Place Bound Bottom")
		(35 "F.Fab" user "Ref Des/Assembly Top")
		(33 "B.Fab" user "Ref Des/Assembly Bottom")
	)
	(footprint ""
		(layer "F.Cu")
		(at 332.25994 -15.979394 -90)
		(property "Reference" "R1266"
			(at 0 0 270)
			(layer "F.SilkS")
			(hide yes)
			(effects
				(font
					(size 1.27 1.27)
				)
			)
		)
		(property "Value" ""
			(at 0 0 270)
			(layer "F.Fab")
			(effects
				(font
					(size 1.27 1.27)
				)
			)
		)
		(duplicate_pad_numbers_are_jumpers no)
		(fp_line
			(start -0.7874 0.4064)
			(end -0.7874 -0.4064)
			(stroke
				(width 0.1524)
				(type default)
			)
			(layer "F.SilkS")
		)
		(fp_line
			(start 0.7874 0.4064)
			(end -0.7874 0.4064)
			(stroke
				(width 0.1524)
				(type default)
			)
			(layer "F.SilkS")
		)
		(fp_line
			(start -0.7874 -0.4064)
			(end 0.7874 -0.4064)
			(stroke
				(width 0.1524)
				(type default)
			)
			(layer "F.SilkS")
		)
		(fp_line
			(start 0.7874 -0.4064)
			(end 0.7874 0.4064)
			(stroke
				(width 0.1524)
				(type default)
			)
			(layer "F.SilkS")
		)
		(fp_line
			(start -0.67945 0.3048)
			(end -0.67945 -0.305054)
			(stroke
				(width 0.1)
				(type default)
			)
			(layer "F.Fab")
		)
		(fp_line
			(start -0.12065 0.3048)
			(end -0.67945 0.3048)
			(stroke
				(width 0.1)
				(type default)
			)
			(layer "F.Fab")
		)
		(fp_line
			(start 0.120396 0.3048)
			(end 0.120396 0.2794)
			(stroke
				(width 0.1)
				(type default)
			)
			(layer "F.Fab")
		)
		(fp_line
			(start 0.67945 0.3048)
			(end 0.120396 0.3048)
			(stroke
				(width 0.1)
				(type default)
			)
			(layer "F.Fab")
		)
		(fp_line
			(start -0.12065 0.2794)
			(end -0.12065 0.3048)
			(stroke
				(width 0.1)
				(type default)
			)
			(layer "F.Fab")
		)
		(fp_line
			(start 0.120396 0.2794)
			(end -0.12065 0.2794)
			(stroke
				(width 0.1)
				(type default)
			)
			(layer "F.Fab")
		)
		(fp_line
			(start -0.12065 -0.2794)
			(end 0.12065 -0.2794)
			(stroke
				(width 0.1)
				(type default)
			)
			(layer "F.Fab")
		)
		(fp_line
			(start 0.12065 -0.2794)
			(end 0.12065 -0.3048)
			(stroke
				(width 0.1)
				(type default)
			)
			(layer "F.Fab")
		)
		(fp_line
			(start 0.12065 -0.3048)
			(end 0.67945 -0.3048)
			(stroke
				(width 0.1)
				(type default)
			)
			(layer "F.Fab")
		)
		(fp_line
			(start 0.67945 -0.3048)
			(end 0.67945 0.3048)
			(stroke
				(width 0.1)
				(type default)
			)
			(layer "F.Fab")
		)
		(fp_line
			(start -0.67945 -0.305054)
			(end -0.12065 -0.305054)
			(stroke
				(width 0.1)
				(type default)
			)
			(layer "F.Fab")
		)
		(fp_line
			(start -0.12065 -0.305054)
			(end -0.12065 -0.2794)
			(stroke
				(width 0.1)
				(type default)
			)
			(layer "F.Fab")
		)
		(pad "1" smd circle
			(at -0.40005 0 270)
			(size 0 0)
			(layers "F.Cu" "F.Mask" "F.Paste")
			(net "P3V3_AUX")
		)
		(pad "2" smd circle
			(at 0.40005 0 270)
			(size 0 0)
			(layers "F.Cu" "F.Mask" "F.Paste")
			(net "BMC_FPGA_LED1_R_N")
		)
	)
	(footprint ""
		(layer "F.Cu")
		(at 127.761492 -156.441902 90)
		(property "Reference" "PC348_3"
			(at 0 0 90)
			(layer "F.SilkS")
			(hide yes)
			(effects
				(font
					(size 1.27 1.27)
				)
			)
		)
		(property "Value" ""
			(at 0 0 90)
			(layer "F.Fab")
			(effects
				(font
					(size 1.27 1.27)
				)
			)
		)
		(duplicate_pad_numbers_are_jumpers no)
		(fp_line
			(start 0.7874 -0.4064)
			(end 0.7874 0.4064)
			(stroke
				(width 0.1524)
				(type default)
			)
			(layer "F.SilkS")
		)
		(fp_line
			(start -0.7874 -0.4064)
			(end 0.7874 -0.4064)
			(stroke
				(width 0.1524)
				(type default)
			)
			(layer "F.SilkS")
		)
		(fp_line
			(start 0.7874 0.4064)
			(end -0.7874 0.4064)
			(stroke
				(width 0.1524)
				(type default)
			)
			(layer "F.SilkS")
		)
		(fp_line
			(start -0.7874 0.4064)
			(end -0.7874 -0.4064)
			(stroke
				(width 0.1524)
				(type default)
			)
			(layer "F.SilkS")
		)
		(fp_line
			(start -0.12065 -0.305054)
			(end -0.12065 -0.2794)
			(stroke
				(width 0.1)
				(type default)
			)
			(layer "F.Fab")
		)
		(fp_line
			(start -0.67945 -0.305054)
			(end -0.12065 -0.305054)
			(stroke
				(width 0.1)
				(type default)
			)
			(layer "F.Fab")
		)
		(fp_line
			(start 0.67945 -0.3048)
			(end 0.67945 0.3048)
			(stroke
				(width 0.1)
				(type default)
			)
			(layer "F.Fab")
		)
		(fp_line
			(start 0.12065 -0.3048)
			(end 0.67945 -0.3048)
			(stroke
				(width 0.1)
				(type default)
			)
			(layer "F.Fab")
		)
		(fp_line
			(start 0.12065 -0.2794)
			(end 0.12065 -0.3048)
			(stroke
				(width 0.1)
				(type default)
			)
			(layer "F.Fab")
		)
		(fp_line
			(start -0.12065 -0.2794)
			(end 0.12065 -0.2794)
			(stroke
				(width 0.1)
				(type default)
			)
			(layer "F.Fab")
		)
		(fp_line
			(start 0.120396 0.2794)
			(end -0.12065 0.2794)
			(stroke
				(width 0.1)
				(type default)
			)
			(layer "F.Fab")
		)
		(fp_line
			(start -0.12065 0.2794)
			(end -0.12065 0.3048)
			(stroke
				(width 0.1)
				(type default)
			)
			(layer "F.Fab")
		)
		(fp_line
			(start 0.67945 0.3048)
			(end 0.120396 0.3048)
			(stroke
				(width 0.1)
				(type default)
			)
			(layer "F.Fab")
		)
		(fp_line
			(start 0.120396 0.3048)
			(end 0.120396 0.2794)
			(stroke
				(width 0.1)
				(type default)
			)
			(layer "F.Fab")
		)
		(fp_line
			(start -0.12065 0.3048)
			(end -0.67945 0.3048)
			(stroke
				(width 0.1)
				(type default)
			)
			(layer "F.Fab")
		)
		(fp_line
			(start -0.67945 0.3048)
			(end -0.67945 -0.305054)
			(stroke
				(width 0.1)
				(type default)
			)
			(layer "F.Fab")
		)
		(pad "1" smd circle
			(at -0.40005 0 90)
			(size 0 0)
			(layers "F.Cu" "F.Mask" "F.Paste")
			(net "SW_P12V_AUX_PVDDCR_SOC_P1_FLT")
		)
		(pad "2" smd circle
			(at 0.40005 0 90)
			(size 0 0)
			(layers "F.Cu" "F.Mask" "F.Paste")
			(net "GND")
		)
	)
	(footprint ""
		(layer "F.Cu")
		(at 138.143234 -79.288894 90)
		(property "Reference" "PC6012"
			(at 0 0 90)
			(layer "F.SilkS")
			(hide yes)
			(effects
				(font
					(size 1.27 1.27)
				)
			)
		)
		(property "Value" ""
			(at 0 0 90)
			(layer "F.Fab")
			(effects
				(font
					(size 1.27 1.27)
				)
			)
		)
		(duplicate_pad_numbers_are_jumpers no)
		(fp_line
			(start 1.524 -0.762)
			(end 1.524 0.762)
			(stroke
				(width 0.1524)
				(type default)
			)
			(layer "F.SilkS")
		)
		(fp_line
			(start -1.524 -0.762)
			(end 1.524 -0.762)
			(stroke
				(width 0.1524)
				(type default)
			)
			(layer "F.SilkS")
		)
		(fp_line
			(start 1.524 0.762)
			(end -1.524 0.762)
			(stroke
				(width 0.1524)
				(type default)
			)
			(layer "F.SilkS")
		)
		(fp_line
			(start -1.524 0.762)
			(end -1.524 -0.762)
			(stroke
				(width 0.1524)
				(type default)
			)
			(layer "F.SilkS")
		)
		(fp_line
			(start 1.1049 -0.724916)
			(end -1.1049 -0.724916)
			(stroke
				(width 0.1)
				(type default)
			)
			(layer "F.Fab")
		)
		(fp_line
			(start -1.1049 -0.724916)
			(end -1.1049 0.724916)
			(stroke
				(width 0.1)
				(type default)
			)
			(layer "F.Fab")
		)
		(fp_line
			(start 1.1049 0.724916)
			(end 1.1049 -0.724916)
			(stroke
				(width 0.1)
				(type default)
			)
			(layer "F.Fab")
		)
		(fp_line
			(start -1.1049 0.724916)
			(end 1.1049 0.724916)
			(stroke
				(width 0.1)
				(type default)
			)
			(layer "F.Fab")
		)
		(pad "1" smd rect
			(at -0.889 0 270)
			(size 1.016 1.27)
			(layers "F.Cu" "F.Mask" "F.Paste")
			(net "SW_P12V_AUX_P1V8_AUX_FLT")
		)
		(pad "2" smd rect
			(at 0.889 0 270)
			(size 1.016 1.27)
			(layers "F.Cu" "F.Mask" "F.Paste")
			(net "GND")
		)
	)
	(footprint ""
		(layer "F.Cu")
		(at 154.277822 -66.04254 180)
		(property "Reference" "C20"
			(at 0 0 180)
			(layer "F.SilkS")
			(hide yes)
			(effects
				(font
					(size 1.27 1.27)
				)
			)
		)
		(property "Value" ""
			(at 0 0 180)
			(layer "F.Fab")
			(effects
				(font
					(size 1.27 1.27)
				)
			)
		)
		(duplicate_pad_numbers_are_jumpers no)
		(fp_line
			(start 0.7874 0.4064)
			(end -0.7874 0.4064)
			(stroke
				(width 0.1524)
				(type default)
			)
			(layer "F.SilkS")
		)
		(fp_line
			(start 0.7874 -0.4064)
			(end 0.7874 0.4064)
			(stroke
				(width 0.1524)
				(type default)
			)
			(layer "F.SilkS")
		)
		(fp_line
			(start -0.7874 0.4064)
			(end -0.7874 -0.4064)
			(stroke
				(width 0.1524)
				(type default)
			)
			(layer "F.SilkS")
		)
		(fp_line
			(start -0.7874 -0.4064)
			(end 0.7874 -0.4064)
			(stroke
				(width 0.1524)
				(type default)
			)
			(layer "F.SilkS")
		)
		(fp_line
			(start 0.67945 0.3048)
			(end 0.120396 0.3048)
			(stroke
				(width 0.1)
				(type default)
			)
			(layer "F.Fab")
		)
		(fp_line
			(start 0.67945 -0.3048)
			(end 0.67945 0.3048)
			(stroke
				(width 0.1)
				(type default)
			)
			(layer "F.Fab")
		)
		(fp_line
			(start 0.12065 -0.2794)
			(end 0.12065 -0.3048)
			(stroke
				(width 0.1)
				(type default)
			)
			(layer "F.Fab")
		)
		(fp_line
			(start 0.12065 -0.3048)
			(end 0.67945 -0.3048)
			(stroke
				(width 0.1)
				(type default)
			)
			(layer "F.Fab")
		)
		(fp_line
			(start 0.120396 0.3048)
			(end 0.120396 0.2794)
			(stroke
				(width 0.1)
				(type default)
			)
			(layer "F.Fab")
		)
		(fp_line
			(start 0.120396 0.2794)
			(end -0.12065 0.2794)
			(stroke
				(width 0.1)
				(type default)
			)
			(layer "F.Fab")
		)
		(fp_line
			(start -0.12065 0.3048)
			(end -0.67945 0.3048)
			(stroke
				(width 0.1)
				(type default)
			)
			(layer "F.Fab")
		)
		(fp_line
			(start -0.12065 0.2794)
			(end -0.12065 0.3048)
			(stroke
				(width 0.1)
				(type default)
			)
			(layer "F.Fab")
		)
		(fp_line
			(start -0.12065 -0.2794)
			(end 0.12065 -0.2794)
			(stroke
				(width 0.1)
				(type default)
			)
			(layer "F.Fab")
		)
		(fp_line
			(start -0.12065 -0.305054)
			(end -0.12065 -0.2794)
			(stroke
				(width 0.1)
				(type default)
			)
			(layer "F.Fab")
		)
		(fp_line
			(start -0.67945 0.3048)
			(end -0.67945 -0.305054)
			(stroke
				(width 0.1)
				(type default)
			)
			(layer "F.Fab")
		)
		(fp_line
			(start -0.67945 -0.305054)
			(end -0.12065 -0.305054)
			(stroke
				(width 0.1)
				(type default)
			)
			(layer "F.Fab")
		)
		(pad "1" smd circle
			(at -0.40005 0 180)
			(size 0 0)
			(layers "F.Cu" "F.Mask" "F.Paste")
			(net "P3V3_AUX")
		)
		(pad "2" smd circle
			(at 0.40005 0 180)
			(size 0 0)
			(layers "F.Cu" "F.Mask" "F.Paste")
			(net "GND")
		)
	)
	(footprint ""
		(layer "F.Cu")
		(at 317.896748 -116.378228 180)
		(property "Reference" "R85"
			(at 0 0 180)
			(layer "F.SilkS")
			(hide yes)
			(effects
				(font
					(size 1.27 1.27)
				)
			)
		)
		(property "Value" ""
			(at 0 0 180)
			(layer "F.Fab")
			(effects
				(font
					(size 1.27 1.27)
				)
			)
		)
		(duplicate_pad_numbers_are_jumpers no)
		(fp_line
			(start 0.7874 0.4064)
			(end -0.7874 0.4064)
			(stroke
				(width 0.1524)
				(type default)
			)
			(layer "F.SilkS")
		)
		(fp_line
			(start 0.7874 -0.4064)
			(end 0.7874 0.4064)
			(stroke
				(width 0.1524)
				(type default)
			)
			(layer "F.SilkS")
		)
		(fp_line
			(start -0.7874 0.4064)
			(end -0.7874 -0.4064)
			(stroke
				(width 0.1524)
				(type default)
			)
			(layer "F.SilkS")
		)
		(fp_line
			(start -0.7874 -0.4064)
			(end 0.7874 -0.4064)
			(stroke
				(width 0.1524)
				(type default)
			)
			(layer "F.SilkS")
		)
		(fp_line
			(start 0.67945 0.3048)
			(end 0.120396 0.3048)
			(stroke
				(width 0.1)
				(type default)
			)
			(layer "F.Fab")
		)
		(fp_line
			(start 0.67945 -0.3048)
			(end 0.67945 0.3048)
			(stroke
				(width 0.1)
				(type default)
			)
			(layer "F.Fab")
		)
		(fp_line
			(start 0.12065 -0.2794)
			(end 0.12065 -0.3048)
			(stroke
				(width 0.1)
				(type default)
			)
			(layer "F.Fab")
		)
		(fp_line
			(start 0.12065 -0.3048)
			(end 0.67945 -0.3048)
			(stroke
				(width 0.1)
				(type default)
			)
			(layer "F.Fab")
		)
		(fp_line
			(start 0.120396 0.3048)
			(end 0.120396 0.2794)
			(stroke
				(width 0.1)
				(type default)
			)
			(layer "F.Fab")
		)
		(fp_line
			(start 0.120396 0.2794)
			(end -0.12065 0.2794)
			(stroke
				(width 0.1)
				(type default)
			)
			(layer "F.Fab")
		)
		(fp_line
			(start -0.12065 0.3048)
			(end -0.67945 0.3048)
			(stroke
				(width 0.1)
				(type default)
			)
			(layer "F.Fab")
		)
		(fp_line
			(start -0.12065 0.2794)
			(end -0.12065 0.3048)
			(stroke
				(width 0.1)
				(type default)
			)
			(layer "F.Fab")
		)
		(fp_line
			(start -0.12065 -0.2794)
			(end 0.12065 -0.2794)
			(stroke
				(width 0.1)
				(type default)
			)
			(layer "F.Fab")
		)
		(fp_line
			(start -0.12065 -0.305054)
			(end -0.12065 -0.2794)
			(stroke
				(width 0.1)
				(type default)
			)
			(layer "F.Fab")
		)
		(fp_line
			(start -0.67945 0.3048)
			(end -0.67945 -0.305054)
			(stroke
				(width 0.1)
				(type default)
			)
			(layer "F.Fab")
		)
		(fp_line
			(start -0.67945 -0.305054)
			(end -0.12065 -0.305054)
			(stroke
				(width 0.1)
				(type default)
			)
			(layer "F.Fab")
		)
		(pad "1" smd circle
			(at -0.40005 0 180)
			(size 0 0)
			(layers "F.Cu" "F.Mask" "F.Paste")
			(net "SMB_FRU_3V3AUX_SCL")
		)
		(pad "2" smd circle
			(at 0.40005 0 180)
			(size 0 0)
			(layers "F.Cu" "F.Mask" "F.Paste")
			(net "SMB_FRU_3V3AUX_R1_SCL")
		)
	)
	(footprint ""
		(layer "F.Cu")
		(at 107.895136 -127.748538 -90)
		(property "Reference" "R1493"
			(at 0 0 270)
			(layer "F.SilkS")
			(hide yes)
			(effects
				(font
					(size 1.27 1.27)
				)
			)
		)
		(property "Value" ""
			(at 0 0 270)
			(layer "F.Fab")
			(effects
				(font
					(size 1.27 1.27)
				)
			)
		)
		(duplicate_pad_numbers_are_jumpers no)
		(fp_line
			(start -0.7874 0.4064)
			(end -0.7874 -0.4064)
			(stroke
				(width 0.1524)
				(type default)
			)
			(layer "F.SilkS")
		)
		(fp_line
			(start 0.7874 0.4064)
			(end -0.7874 0.4064)
			(stroke
				(width 0.1524)
				(type default)
			)
			(layer "F.SilkS")
		)
		(fp_line
			(start -0.7874 -0.4064)
			(end 0.7874 -0.4064)
			(stroke
				(width 0.1524)
				(type default)
			)
			(layer "F.SilkS")
		)
		(fp_line
			(start 0.7874 -0.4064)
			(end 0.7874 0.4064)
			(stroke
				(width 0.1524)
				(type default)
			)
			(layer "F.SilkS")
		)
		(fp_line
			(start -0.67945 0.3048)
			(end -0.67945 -0.305054)
			(stroke
				(width 0.1)
				(type default)
			)
			(layer "F.Fab")
		)
		(fp_line
			(start -0.12065 0.3048)
			(end -0.67945 0.3048)
			(stroke
				(width 0.1)
				(type default)
			)
			(layer "F.Fab")
		)
		(fp_line
			(start 0.120396 0.3048)
			(end 0.120396 0.2794)
			(stroke
				(width 0.1)
				(type default)
			)
			(layer "F.Fab")
		)
		(fp_line
			(start 0.67945 0.3048)
			(end 0.120396 0.3048)
			(stroke
				(width 0.1)
				(type default)
			)
			(layer "F.Fab")
		)
		(fp_line
			(start -0.12065 0.2794)
			(end -0.12065 0.3048)
			(stroke
				(width 0.1)
				(type default)
			)
			(layer "F.Fab")
		)
		(fp_line
			(start 0.120396 0.2794)
			(end -0.12065 0.2794)
			(stroke
				(width 0.1)
				(type default)
			)
			(layer "F.Fab")
		)
		(fp_line
			(start -0.12065 -0.2794)
			(end 0.12065 -0.2794)
			(stroke
				(width 0.1)
				(type default)
			)
			(layer "F.Fab")
		)
		(fp_line
			(start 0.12065 -0.2794)
			(end 0.12065 -0.3048)
			(stroke
				(width 0.1)
				(type default)
			)
			(layer "F.Fab")
		)
		(fp_line
			(start 0.12065 -0.3048)
			(end 0.67945 -0.3048)
			(stroke
				(width 0.1)
				(type default)
			)
			(layer "F.Fab")
		)
		(fp_line
			(start 0.67945 -0.3048)
			(end 0.67945 0.3048)
			(stroke
				(width 0.1)
				(type default)
			)
			(layer "F.Fab")
		)
		(fp_line
			(start -0.67945 -0.305054)
			(end -0.12065 -0.305054)
			(stroke
				(width 0.1)
				(type default)
			)
			(layer "F.Fab")
		)
		(fp_line
			(start -0.12065 -0.305054)
			(end -0.12065 -0.2794)
			(stroke
				(width 0.1)
				(type default)
			)
			(layer "F.Fab")
		)
		(pad "1" smd circle
			(at -0.40005 0 270)
			(size 0 0)
			(layers "F.Cu" "F.Mask" "F.Paste")
			(net "P1V8_AUX")
		)
		(pad "2" smd circle
			(at 0.40005 0 270)
			(size 0 0)
			(layers "F.Cu" "F.Mask" "F.Paste")
			(net "PWRGD_P3V3_R1")
		)
	)
)
